# T6G (Grand Teton) — schematic netlist excerpt (pin names and nets, part order shuffled) for the footprints in the layout excerpt that follows; sources: Cadence DE-HDL packaged netlist, KiCad conversion of 04192023_DAF0TMB3IC0_F0TG_MB_C_brd_V02_OCP.brd

R590  Q_RES  4.7K 5% CHIP  pkg 0402LF  page 34 : A = P3V3_AUX ; B = SMB_CPU0_4_XLTR_SDA
C1575  Q_CAP_DIFFBUS  DIFF BUS_0.22UF 6.3V 20% X6S  pkg C0201  page 65 : \1\ = P5E_CPU0_G3_TX_C_DP<2> ; \2\ = P5E_CPU0_G3_TX_DP<2>
C2014  Q_CAP  0.1UF 25V 10% X7R  pkg 0402  page 237 : A = P3V3_AUX ; B = GND

(kicad_pcb
	(version 20260206)
	(generator "pcbnew")
	(generator_version "10.0")
	(general
		(thickness 1.6)
		(legacy_teardrops no)
	)
	(paper "A4")
	(title_block
		(title "04192023_DAF0TMB3IC0_F0TG_MB_C_brd_V02_OCP.brd")
		(comment 1 "Grand Teton / footprints 1580-1583 of 8354")
	)
	(layers
		(0 "F.Cu" signal "TOP")
		(4 "In1.Cu" signal "GND")
		(6 "In2.Cu" signal "IN1")
		(8 "In3.Cu" signal "GND1")
		(10 "In4.Cu" signal "IN2")
		(12 "In5.Cu" signal "GND2")
		(14 "In6.Cu" signal "IN3")
		(16 "In7.Cu" signal "GND3")
		(18 "In8.Cu" signal "VCC")
		(20 "In9.Cu" signal "VCC1")
		(22 "In10.Cu" signal "GND4")
		(24 "In11.Cu" signal "IN4")
		(26 "In12.Cu" signal "GND5")
		(28 "In13.Cu" signal "IN5")
		(30 "In14.Cu" signal "GND6")
		(32 "In15.Cu" signal "IN6")
		(34 "In16.Cu" signal "GND7")
		(2 "B.Cu" signal "BOTTOM")
		(9 "F.Adhes" user "F.Adhesive")
		(11 "B.Adhes" user "B.Adhesive")
		(13 "F.Paste" user "Package Geometry/Pastemask Top")
		(15 "B.Paste" user "Package Geometry/Pastemask Bottom")
		(5 "F.SilkS" user "Ref Des/Silkscreen Top")
		(7 "B.SilkS" user "Ref Des/Silkscreen Bottom")
		(1 "F.Mask" user "Board Geometry/Soldermask Top")
		(3 "B.Mask" user "Board Geometry/Soldermask Bottom")
		(17 "Dwgs.User" user "User.Drawings")
		(19 "Cmts.User" user "User.Comments")
		(21 "Eco1.User" user "User.Eco1")
		(23 "Eco2.User" user "User.Eco2")
		(25 "Edge.Cuts" user "Board Geometry/Outline")
		(27 "Margin" user)
		(31 "F.CrtYd" user "Package Geometry/Place Bound Top")
		(29 "B.CrtYd" user "Package Geometry/Place Bound Bottom")
		(35 "F.Fab" user "Ref Des/Assembly Top")
		(33 "B.Fab" user "Ref Des/Assembly Bottom")
	)
	(footprint ""
		(layer "F.Cu")
		(at 209.959956 -37.769292 90)
		(property "Reference" "C2014"
			(at 0 0 90)
			(layer "F.SilkS")
			(hide yes)
			(effects
				(font
					(size 1.27 1.27)
				)
			)
		)
		(property "Value" ""
			(at 0 0 90)
			(layer "F.Fab")
			(effects
				(font
					(size 1.27 1.27)
				)
			)
		)
		(duplicate_pad_numbers_are_jumpers no)
		(fp_line
			(start 0.7874 -0.4064)
			(end 0.7874 0.4064)
			(stroke
				(width 0.1524)
				(type default)
			)
			(layer "F.SilkS")
		)
		(fp_line
			(start -0.7874 -0.4064)
			(end 0.7874 -0.4064)
			(stroke
				(width 0.1524)
				(type default)
			)
			(layer "F.SilkS")
		)
		(fp_line
			(start 0.7874 0.4064)
			(end -0.7874 0.4064)
			(stroke
				(width 0.1524)
				(type default)
			)
			(layer "F.SilkS")
		)
		(fp_line
			(start -0.7874 0.4064)
			(end -0.7874 -0.4064)
			(stroke
				(width 0.1524)
				(type default)
			)
			(layer "F.SilkS")
		)
		(fp_line
			(start -0.12065 -0.305054)
			(end -0.12065 -0.2794)
			(stroke
				(width 0.1)
				(type default)
			)
			(layer "F.Fab")
		)
		(fp_line
			(start -0.67945 -0.305054)
			(end -0.12065 -0.305054)
			(stroke
				(width 0.1)
				(type default)
			)
			(layer "F.Fab")
		)
		(fp_line
			(start 0.67945 -0.3048)
			(end 0.67945 0.3048)
			(stroke
				(width 0.1)
				(type default)
			)
			(layer "F.Fab")
		)
		(fp_line
			(start 0.12065 -0.3048)
			(end 0.67945 -0.3048)
			(stroke
				(width 0.1)
				(type default)
			)
			(layer "F.Fab")
		)
		(fp_line
			(start 0.12065 -0.2794)
			(end 0.12065 -0.3048)
			(stroke
				(width 0.1)
				(type default)
			)
			(layer "F.Fab")
		)
		(fp_line
			(start -0.12065 -0.2794)
			(end 0.12065 -0.2794)
			(stroke
				(width 0.1)
				(type default)
			)
			(layer "F.Fab")
		)
		(fp_line
			(start 0.120396 0.2794)
			(end -0.12065 0.2794)
			(stroke
				(width 0.1)
				(type default)
			)
			(layer "F.Fab")
		)
		(fp_line
			(start -0.12065 0.2794)
			(end -0.12065 0.3048)
			(stroke
				(width 0.1)
				(type default)
			)
			(layer "F.Fab")
		)
		(fp_line
			(start 0.67945 0.3048)
			(end 0.120396 0.3048)
			(stroke
				(width 0.1)
				(type default)
			)
			(layer "F.Fab")
		)
		(fp_line
			(start 0.120396 0.3048)
			(end 0.120396 0.2794)
			(stroke
				(width 0.1)
				(type default)
			)
			(layer "F.Fab")
		)
		(fp_line
			(start -0.12065 0.3048)
			(end -0.67945 0.3048)
			(stroke
				(width 0.1)
				(type default)
			)
			(layer "F.Fab")
		)
		(fp_line
			(start -0.67945 0.3048)
			(end -0.67945 -0.305054)
			(stroke
				(width 0.1)
				(type default)
			)
			(layer "F.Fab")
		)
		(pad "1" smd circle
			(at -0.40005 0 90)
			(size 0 0)
			(layers "F.Cu" "F.Mask" "F.Paste")
			(net "P3V3_AUX")
		)
		(pad "2" smd circle
			(at 0.40005 0 90)
			(size 0 0)
			(layers "F.Cu" "F.Mask" "F.Paste")
			(net "GND")
		)
	)
	(footprint ""
		(layer "F.Cu")
		(at 427.5836 -17.624298 90)
		(property "Reference" "C1575"
			(at 0 0 90)
			(layer "F.SilkS")
			(hide yes)
			(effects
				(font
					(size 1.27 1.27)
				)
			)
		)
		(property "Value" ""
			(at 0 0 90)
			(layer "F.Fab")
			(effects
				(font
					(size 1.27 1.27)
				)
			)
		)
		(duplicate_pad_numbers_are_jumpers no)
		(fp_line
			(start 0.299974 -0.150114)
			(end 0.299974 0.150114)
			(stroke
				(width 0.1)
				(type default)
			)
			(layer "F.Fab")
		)
		(fp_line
			(start -0.299974 -0.150114)
			(end 0.299974 -0.150114)
			(stroke
				(width 0.1)
				(type default)
			)
			(layer "F.Fab")
		)
		(fp_line
			(start 0.299974 0.150114)
			(end -0.299974 0.150114)
			(stroke
				(width 0.1)
				(type default)
			)
			(layer "F.Fab")
		)
		(fp_line
			(start -0.299974 0.150114)
			(end -0.299974 -0.150114)
			(stroke
				(width 0.1)
				(type default)
			)
			(layer "F.Fab")
		)
		(pad "1" smd rect
			(at -0.2667 0 90)
			(size 0.3048 0.381)
			(layers "F.Cu" "F.Mask" "F.Paste")
			(net "P5E_CPU0_G3_TX_C_DP<2>")
		)
		(pad "2" smd rect
			(at 0.2667 0 90)
			(size 0.3048 0.381)
			(layers "F.Cu" "F.Mask" "F.Paste")
			(net "P5E_CPU0_G3_TX_DP<2>")
		)
	)
	(footprint ""
		(layer "F.Cu")
		(at 177.544984 -147.086574 90)
		(property "Reference" "R590"
			(at 0 0 90)
			(layer "F.SilkS")
			(hide yes)
			(effects
				(font
					(size 1.27 1.27)
				)
			)
		)
		(property "Value" ""
			(at 0 0 90)
			(layer "F.Fab")
			(effects
				(font
					(size 1.27 1.27)
				)
			)
		)
		(duplicate_pad_numbers_are_jumpers no)
		(fp_line
			(start 0.7874 -0.4064)
			(end 0.7874 0.4064)
			(stroke
				(width 0.1524)
				(type default)
			)
			(layer "F.SilkS")
		)
		(fp_line
			(start -0.7874 -0.4064)
			(end 0.7874 -0.4064)
			(stroke
				(width 0.1524)
				(type default)
			)
			(layer "F.SilkS")
		)
		(fp_line
			(start 0.7874 0.4064)
			(end -0.7874 0.4064)
			(stroke
				(width 0.1524)
				(type default)
			)
			(layer "F.SilkS")
		)
		(fp_line
			(start -0.7874 0.4064)
			(end -0.7874 -0.4064)
			(stroke
				(width 0.1524)
				(type default)
			)
			(layer "F.SilkS")
		)
		(fp_line
			(start -0.12065 -0.305054)
			(end -0.12065 -0.2794)
			(stroke
				(width 0.1)
				(type default)
			)
			(layer "F.Fab")
		)
		(fp_line
			(start -0.67945 -0.305054)
			(end -0.12065 -0.305054)
			(stroke
				(width 0.1)
				(type default)
			)
			(layer "F.Fab")
		)
		(fp_line
			(start 0.67945 -0.3048)
			(end 0.67945 0.3048)
			(stroke
				(width 0.1)
				(type default)
			)
			(layer "F.Fab")
		)
		(fp_line
			(start 0.12065 -0.3048)
			(end 0.67945 -0.3048)
			(stroke
				(width 0.1)
				(type default)
			)
			(layer "F.Fab")
		)
		(fp_line
			(start 0.12065 -0.2794)
			(end 0.12065 -0.3048)
			(stroke
				(width 0.1)
				(type default)
			)
			(layer "F.Fab")
		)
		(fp_line
			(start -0.12065 -0.2794)
			(end 0.12065 -0.2794)
			(stroke
				(width 0.1)
				(type default)
			)
			(layer "F.Fab")
		)
		(fp_line
			(start 0.120396 0.2794)
			(end -0.12065 0.2794)
			(stroke
				(width 0.1)
				(type default)
			)
			(layer "F.Fab")
		)
		(fp_line
			(start -0.12065 0.2794)
			(end -0.12065 0.3048)
			(stroke
				(width 0.1)
				(type default)
			)
			(layer "F.Fab")
		)
		(fp_line
			(start 0.67945 0.3048)
			(end 0.120396 0.3048)
			(stroke
				(width 0.1)
				(type default)
			)
			(layer "F.Fab")
		)
		(fp_line
			(start 0.120396 0.3048)
			(end 0.120396 0.2794)
			(stroke
				(width 0.1)
				(type default)
			)
			(layer "F.Fab")
		)
		(fp_line
			(start -0.12065 0.3048)
			(end -0.67945 0.3048)
			(stroke
				(width 0.1)
				(type default)
			)
			(layer "F.Fab")
		)
		(fp_line
			(start -0.67945 0.3048)
			(end -0.67945 -0.305054)
			(stroke
				(width 0.1)
				(type default)
			)
			(layer "F.Fab")
		)
		(pad "1" smd circle
			(at -0.40005 0 90)
			(size 0 0)
			(layers "F.Cu" "F.Mask" "F.Paste")
			(net "P3V3_AUX")
		)
		(pad "2" smd circle
			(at 0.40005 0 90)
			(size 0 0)
			(layers "F.Cu" "F.Mask" "F.Paste")
			(net "SMB_CPU0_4_XLTR_SDA")
		)
	)
	(footprint ""
		(layer "F.Cu")
		(at 40.116506 19.444716 -90)
		(property "Reference" "U25_BP"
			(at 0 0 270)
			(layer "F.SilkS")
			(hide yes)
			(effects
				(font
					(size 1.27 1.27)
				)
			)
		)
		(property "Value" ""
			(at 0 0 270)
			(layer "F.Fab")
			(effects
				(font
					(size 1.27 1.27)
				)
			)
		)
		(duplicate_pad_numbers_are_jumpers no)
		(pad "1" smd circle
			(at 0 0 270)
			(size 0.762 0.762)
			(layers "F.Cu" "F.Mask" "F.Paste")
			(net "Net_10789")
		)
	)
)
